(kicad_pcb
	(version 20260206)
	(generator "pcbnew")
	(generator_version "10.0")
	(general
		(thickness 1.6)
		(legacy_teardrops no)
	)
	(paper "A4")
	(title_block
		(title "01162023_DA0F0TEBIF0_F0T_Expander_BD_F_brd_V02_OCP.brd")
		(comment 1 "Grand Teton / footprints 7147-7156 of 9728")
	)
	(layers
		(0 "F.Cu" signal "TOP")
		(4 "In1.Cu" signal "GND")
		(6 "In2.Cu" signal "VCC")
		(8 "In3.Cu" signal "VCC1")
		(10 "In4.Cu" signal "GND1")
		(12 "In5.Cu" signal "IN1")
		(14 "In6.Cu" signal "GND2")
		(16 "In7.Cu" signal "IN2")
		(18 "In8.Cu" signal "GND3")
		(20 "In9.Cu" signal "IN3")
		(22 "In10.Cu" signal "GND4")
		(24 "In11.Cu" signal "IN4")
		(26 "In12.Cu" signal "GND5")
		(28 "In13.Cu" signal "IN5")
		(30 "In14.Cu" signal "GND6")
		(32 "In15.Cu" signal "IN6")
		(34 "In16.Cu" signal "GND7")
		(2 "B.Cu" signal "BOTTOM")
		(9 "F.Adhes" user "F.Adhesive")
		(11 "B.Adhes" user "B.Adhesive")
		(13 "F.Paste" user "Package Geometry/Pastemask Top")
		(15 "B.Paste" user "Package Geometry/Pastemask Bottom")
		(5 "F.SilkS" user "Ref Des/Silkscreen Top")
		(7 "B.SilkS" user "Ref Des/Silkscreen Bottom")
		(1 "F.Mask" user "Board Geometry/Soldermask Top")
		(3 "B.Mask" user "Board Geometry/Soldermask Bottom")
		(17 "Dwgs.User" user "User.Drawings")
		(19 "Cmts.User" user "User.Comments")
		(21 "Eco1.User" user "User.Eco1")
		(23 "Eco2.User" user "User.Eco2")
		(25 "Edge.Cuts" user "Board Geometry/Outline")
		(27 "Margin" user)
		(31 "F.CrtYd" user "Package Geometry/Place Bound Top")
		(29 "B.CrtYd" user "Package Geometry/Place Bound Bottom")
		(35 "F.Fab" user "Ref Des/Assembly Top")
		(33 "B.Fab" user "Ref Des/Assembly Bottom")
	)
	(footprint ""
		(layer "B.Cu")
		(at 77.541882 -95.989648 180)
		(property "Reference" "R62"
			(at 0 0 0)
			(layer "B.SilkS")
			(hide yes)
			(effects
				(font
					(size 1.27 1.27)
				)
				(justify mirror)
			)
		)
		(property "Value" ""
			(at 0 0 0)
			(layer "B.Fab")
			(effects
				(font
					(size 1.27 1.27)
				)
				(justify mirror)
			)
		)
		(duplicate_pad_numbers_are_jumpers no)
		(fp_line
			(start 0.7874 0.4064)
			(end 0.7874 -0.4064)
			(stroke
				(width 0.1524)
				(type default)
			)
			(layer "B.SilkS")
		)
		(fp_line
			(start 0.7874 -0.4064)
			(end -0.7874 -0.4064)
			(stroke
				(width 0.1524)
				(type default)
			)
			(layer "B.SilkS")
		)
		(fp_line
			(start -0.7874 0.4064)
			(end 0.7874 0.4064)
			(stroke
				(width 0.1524)
				(type default)
			)
			(layer "B.SilkS")
		)
		(fp_line
			(start -0.7874 -0.4064)
			(end -0.7874 0.4064)
			(stroke
				(width 0.1524)
				(type default)
			)
			(layer "B.SilkS")
		)
		(fp_line
			(start 0.67945 0.3048)
			(end 0.67945 -0.305054)
			(stroke
				(width 0.1)
				(type default)
			)
			(layer "B.Fab")
		)
		(fp_line
			(start 0.67945 -0.305054)
			(end 0.12065 -0.305054)
			(stroke
				(width 0.1)
				(type default)
			)
			(layer "B.Fab")
		)
		(fp_line
			(start 0.12065 0.3048)
			(end 0.67945 0.3048)
			(stroke
				(width 0.1)
				(type default)
			)
			(layer "B.Fab")
		)
		(fp_line
			(start 0.12065 0.2794)
			(end 0.12065 0.3048)
			(stroke
				(width 0.1)
				(type default)
			)
			(layer "B.Fab")
		)
		(fp_line
			(start 0.12065 -0.2794)
			(end -0.12065 -0.2794)
			(stroke
				(width 0.1)
				(type default)
			)
			(layer "B.Fab")
		)
		(fp_line
			(start 0.12065 -0.305054)
			(end 0.12065 -0.2794)
			(stroke
				(width 0.1)
				(type default)
			)
			(layer "B.Fab")
		)
		(fp_line
			(start -0.120396 0.3048)
			(end -0.120396 0.2794)
			(stroke
				(width 0.1)
				(type default)
			)
			(layer "B.Fab")
		)
		(fp_line
			(start -0.120396 0.2794)
			(end 0.12065 0.2794)
			(stroke
				(width 0.1)
				(type default)
			)
			(layer "B.Fab")
		)
		(fp_line
			(start -0.12065 -0.2794)
			(end -0.12065 -0.3048)
			(stroke
				(width 0.1)
				(type default)
			)
			(layer "B.Fab")
		)
		(fp_line
			(start -0.12065 -0.3048)
			(end -0.67945 -0.3048)
			(stroke
				(width 0.1)
				(type default)
			)
			(layer "B.Fab")
		)
		(fp_line
			(start -0.67945 0.3048)
			(end -0.120396 0.3048)
			(stroke
				(width 0.1)
				(type default)
			)
			(layer "B.Fab")
		)
		(fp_line
			(start -0.67945 -0.3048)
			(end -0.67945 0.3048)
			(stroke
				(width 0.1)
				(type default)
			)
			(layer "B.Fab")
		)
		(pad "1" smd circle
			(at 0.40005 0)
			(size 0 0)
			(layers "B.Cu" "B.Mask" "B.Paste")
			(net "NIC1_LD_N")
		)
		(pad "2" smd circle
			(at -0.40005 0)
			(size 0 0)
			(layers "B.Cu" "B.Mask" "B.Paste")
			(net "P3V3_NIC1")
		)
	)
	(footprint ""
		(layer "B.Cu")
		(at 401.774914 -286.399732 90)
		(property "Reference" "C3500"
			(at 0 0 90)
			(layer "B.SilkS")
			(hide yes)
			(effects
				(font
					(size 1.27 1.27)
				)
				(justify mirror)
			)
		)
		(property "Value" ""
			(at 0 0 90)
			(layer "B.Fab")
			(effects
				(font
					(size 1.27 1.27)
				)
				(justify mirror)
			)
		)
		(duplicate_pad_numbers_are_jumpers no)
		(fp_line
			(start 0.299974 -0.150114)
			(end -0.299974 -0.150114)
			(stroke
				(width 0.1)
				(type default)
			)
			(layer "B.Fab")
		)
		(fp_line
			(start -0.299974 -0.150114)
			(end -0.299974 0.150114)
			(stroke
				(width 0.1)
				(type default)
			)
			(layer "B.Fab")
		)
		(fp_line
			(start 0.299974 0.150114)
			(end 0.299974 -0.150114)
			(stroke
				(width 0.1)
				(type default)
			)
			(layer "B.Fab")
		)
		(fp_line
			(start -0.299974 0.150114)
			(end 0.299974 0.150114)
			(stroke
				(width 0.1)
				(type default)
			)
			(layer "B.Fab")
		)
		(pad "1" smd rect
			(at 0.2667 0 270)
			(size 0.3048 0.381)
			(layers "B.Cu" "B.Mask" "B.Paste")
			(net "P1V25_SERDES_VDDPLL_PEX3")
		)
		(pad "2" smd rect
			(at -0.2667 0 270)
			(size 0.3048 0.381)
			(layers "B.Cu" "B.Mask" "B.Paste")
			(net "GND")
		)
	)
	(footprint ""
		(layer "B.Cu")
		(at 62.499748 -288.299906 90)
		(property "Reference" "C2919"
			(at 0 0 90)
			(layer "B.SilkS")
			(hide yes)
			(effects
				(font
					(size 1.27 1.27)
				)
				(justify mirror)
			)
		)
		(property "Value" ""
			(at 0 0 90)
			(layer "B.Fab")
			(effects
				(font
					(size 1.27 1.27)
				)
				(justify mirror)
			)
		)
		(duplicate_pad_numbers_are_jumpers no)
		(fp_line
			(start 0.299974 -0.150114)
			(end -0.299974 -0.150114)
			(stroke
				(width 0.1)
				(type default)
			)
			(layer "B.Fab")
		)
		(fp_line
			(start -0.299974 -0.150114)
			(end -0.299974 0.150114)
			(stroke
				(width 0.1)
				(type default)
			)
			(layer "B.Fab")
		)
		(fp_line
			(start 0.299974 0.150114)
			(end 0.299974 -0.150114)
			(stroke
				(width 0.1)
				(type default)
			)
			(layer "B.Fab")
		)
		(fp_line
			(start -0.299974 0.150114)
			(end 0.299974 0.150114)
			(stroke
				(width 0.1)
				(type default)
			)
			(layer "B.Fab")
		)
		(pad "1" smd rect
			(at 0.2667 0 270)
			(size 0.3048 0.381)
			(layers "B.Cu" "B.Mask" "B.Paste")
			(net "P1V25_PEX0")
		)
		(pad "2" smd rect
			(at -0.2667 0 270)
			(size 0.3048 0.381)
			(layers "B.Cu" "B.Mask" "B.Paste")
			(net "GND")
		)
	)
	(footprint ""
		(layer "B.Cu")
		(at 408.899868 -292.099746 90)
		(property "Reference" "C2001"
			(at 0 0 90)
			(layer "B.SilkS")
			(hide yes)
			(effects
				(font
					(size 1.27 1.27)
				)
				(justify mirror)
			)
		)
		(property "Value" ""
			(at 0 0 90)
			(layer "B.Fab")
			(effects
				(font
					(size 1.27 1.27)
				)
				(justify mirror)
			)
		)
		(duplicate_pad_numbers_are_jumpers no)
		(fp_line
			(start 0.299974 -0.150114)
			(end -0.299974 -0.150114)
			(stroke
				(width 0.1)
				(type default)
			)
			(layer "B.Fab")
		)
		(fp_line
			(start -0.299974 -0.150114)
			(end -0.299974 0.150114)
			(stroke
				(width 0.1)
				(type default)
			)
			(layer "B.Fab")
		)
		(fp_line
			(start 0.299974 0.150114)
			(end 0.299974 -0.150114)
			(stroke
				(width 0.1)
				(type default)
			)
			(layer "B.Fab")
		)
		(fp_line
			(start -0.299974 0.150114)
			(end 0.299974 0.150114)
			(stroke
				(width 0.1)
				(type default)
			)
			(layer "B.Fab")
		)
		(pad "1" smd rect
			(at 0.2667 0 270)
			(size 0.3048 0.381)
			(layers "B.Cu" "B.Mask" "B.Paste")
			(net "P0V8_SERDES_VDDA_PEX3")
		)
		(pad "2" smd rect
			(at -0.2667 0 270)
			(size 0.3048 0.381)
			(layers "B.Cu" "B.Mask" "B.Paste")
			(net "GND")
		)
	)
	(footprint ""
		(layer "B.Cu")
		(at 340.093808 -223.187006)
		(property "Reference" "C2031"
			(at 0 0 0)
			(layer "B.SilkS")
			(hide yes)
			(effects
				(font
					(size 1.27 1.27)
				)
				(justify mirror)
			)
		)
		(property "Value" ""
			(at 0 0 0)
			(layer "B.Fab")
			(effects
				(font
					(size 1.27 1.27)
				)
				(justify mirror)
			)
		)
		(duplicate_pad_numbers_are_jumpers no)
		(fp_line
			(start -0.69215 -0.2921)
			(end -0.69215 0.2921)
			(stroke
				(width 0.1524)
				(type default)
			)
			(layer "B.SilkS")
		)
		(fp_line
			(start -0.69215 0.2921)
			(end 0.69215 0.2921)
			(stroke
				(width 0.1524)
				(type default)
			)
			(layer "B.SilkS")
		)
		(fp_line
			(start 0.69215 -0.2921)
			(end -0.69215 -0.2921)
			(stroke
				(width 0.1524)
				(type default)
			)
			(layer "B.SilkS")
		)
		(fp_line
			(start 0.69215 0.2921)
			(end 0.69215 -0.2921)
			(stroke
				(width 0.1524)
				(type default)
			)
			(layer "B.SilkS")
		)
		(fp_line
			(start -0.51435 -0.2794)
			(end -0.51435 0.2794)
			(stroke
				(width 0.1)
				(type default)
			)
			(layer "B.Fab")
		)
		(fp_line
			(start -0.51435 0.2794)
			(end 0.51435 0.2794)
			(stroke
				(width 0.1)
				(type default)
			)
			(layer "B.Fab")
		)
		(fp_line
			(start 0.51435 -0.2794)
			(end -0.51435 -0.2794)
			(stroke
				(width 0.1)
				(type default)
			)
			(layer "B.Fab")
		)
		(fp_line
			(start 0.51435 0.2794)
			(end 0.51435 -0.2794)
			(stroke
				(width 0.1)
				(type default)
			)
			(layer "B.Fab")
		)
		(pad "1" smd circle
			(at 0.40005 0 180)
			(size 0 0)
			(layers "B.Cu" "B.Mask" "B.Paste")
			(net "P3V3_FPGA_VCCIO0")
		)
		(pad "2" smd circle
			(at -0.40005 0 180)
			(size 0 0)
			(layers "B.Cu" "B.Mask" "B.Paste")
			(net "GND")
		)
		(zone
			(layer "B.Cu")
			(hatch none 0.5)
			(connect_pads
				(clearance 0)
			)
			(min_thickness 0.25)
			(keepout
				(tracks not_allowed)
				(vias allowed)
				(pads allowed)
				(copperpour not_allowed)
				(footprints allowed)
			)
			(placement
				(enabled no)
				(sheetname "")
			)
			(fill
				(thermal_gap 0.5)
				(thermal_bridge_width 0.5)
				(island_removal_mode 0)
			)
			(polygon
				(pts
					(xy 340.284308 -223.099376) (xy 340.192868 -223.04121) (xy 339.993478 -223.04121) (xy 339.903308 -223.099376)
					(xy 339.903308 -223.274636) (xy 339.993478 -223.333056) (xy 340.192868 -223.333056) (xy 340.284308 -223.27489)
				)
			)
		)
	)
	(footprint ""
		(layer "B.Cu")
		(at 297.549824 -292.099746 90)
		(property "Reference" "C1680"
			(at 0 0 90)
			(layer "B.SilkS")
			(hide yes)
			(effects
				(font
					(size 1.27 1.27)
				)
				(justify mirror)
			)
		)
		(property "Value" ""
			(at 0 0 90)
			(layer "B.Fab")
			(effects
				(font
					(size 1.27 1.27)
				)
				(justify mirror)
			)
		)
		(duplicate_pad_numbers_are_jumpers no)
		(fp_line
			(start 0.299974 -0.150114)
			(end -0.299974 -0.150114)
			(stroke
				(width 0.1)
				(type default)
			)
			(layer "B.Fab")
		)
		(fp_line
			(start -0.299974 -0.150114)
			(end -0.299974 0.150114)
			(stroke
				(width 0.1)
				(type default)
			)
			(layer "B.Fab")
		)
		(fp_line
			(start 0.299974 0.150114)
			(end 0.299974 -0.150114)
			(stroke
				(width 0.1)
				(type default)
			)
			(layer "B.Fab")
		)
		(fp_line
			(start -0.299974 0.150114)
			(end 0.299974 0.150114)
			(stroke
				(width 0.1)
				(type default)
			)
			(layer "B.Fab")
		)
		(pad "1" smd rect
			(at 0.2667 0 270)
			(size 0.3048 0.381)
			(layers "B.Cu" "B.Mask" "B.Paste")
			(net "P0V8_SERDES_VDDA_PEX2")
		)
		(pad "2" smd rect
			(at -0.2667 0 270)
			(size 0.3048 0.381)
			(layers "B.Cu" "B.Mask" "B.Paste")
			(net "GND")
		)
	)
	(footprint ""
		(layer "B.Cu")
		(at 262.96239 -85.784944)
		(property "Reference" "C2648"
			(at 0 0 0)
			(layer "B.SilkS")
			(hide yes)
			(effects
				(font
					(size 1.27 1.27)
				)
				(justify mirror)
			)
		)
		(property "Value" ""
			(at 0 0 0)
			(layer "B.Fab")
			(effects
				(font
					(size 1.27 1.27)
				)
				(justify mirror)
			)
		)
		(duplicate_pad_numbers_are_jumpers no)
		(fp_line
			(start -0.7874 -0.4064)
			(end -0.7874 0.4064)
			(stroke
				(width 0.1524)
				(type default)
			)
			(layer "B.SilkS")
		)
		(fp_line
			(start -0.7874 0.4064)
			(end 0.7874 0.4064)
			(stroke
				(width 0.1524)
				(type default)
			)
			(layer "B.SilkS")
		)
		(fp_line
			(start 0.7874 -0.4064)
			(end -0.7874 -0.4064)
			(stroke
				(width 0.1524)
				(type default)
			)
			(layer "B.SilkS")
		)
		(fp_line
			(start 0.7874 0.4064)
			(end 0.7874 -0.4064)
			(stroke
				(width 0.1524)
				(type default)
			)
			(layer "B.SilkS")
		)
		(fp_line
			(start -0.67945 -0.3048)
			(end -0.67945 0.3048)
			(stroke
				(width 0.1)
				(type default)
			)
			(layer "B.Fab")
		)
		(fp_line
			(start -0.67945 0.3048)
			(end -0.120396 0.3048)
			(stroke
				(width 0.1)
				(type default)
			)
			(layer "B.Fab")
		)
		(fp_line
			(start -0.12065 -0.3048)
			(end -0.67945 -0.3048)
			(stroke
				(width 0.1)
				(type default)
			)
			(layer "B.Fab")
		)
		(fp_line
			(start -0.12065 -0.2794)
			(end -0.12065 -0.3048)
			(stroke
				(width 0.1)
				(type default)
			)
			(layer "B.Fab")
		)
		(fp_line
			(start -0.120396 0.2794)
			(end 0.12065 0.2794)
			(stroke
				(width 0.1)
				(type default)
			)
			(layer "B.Fab")
		)
		(fp_line
			(start -0.120396 0.3048)
			(end -0.120396 0.2794)
			(stroke
				(width 0.1)
				(type default)
			)
			(layer "B.Fab")
		)
		(fp_line
			(start 0.12065 -0.305054)
			(end 0.12065 -0.2794)
			(stroke
				(width 0.1)
				(type default)
			)
			(layer "B.Fab")
		)
		(fp_line
			(start 0.12065 -0.2794)
			(end -0.12065 -0.2794)
			(stroke
				(width 0.1)
				(type default)
			)
			(layer "B.Fab")
		)
		(fp_line
			(start 0.12065 0.2794)
			(end 0.12065 0.3048)
			(stroke
				(width 0.1)
				(type default)
			)
			(layer "B.Fab")
		)
		(fp_line
			(start 0.12065 0.3048)
			(end 0.67945 0.3048)
			(stroke
				(width 0.1)
				(type default)
			)
			(layer "B.Fab")
		)
		(fp_line
			(start 0.67945 -0.305054)
			(end 0.12065 -0.305054)
			(stroke
				(width 0.1)
				(type default)
			)
			(layer "B.Fab")
		)
		(fp_line
			(start 0.67945 0.3048)
			(end 0.67945 -0.305054)
			(stroke
				(width 0.1)
				(type default)
			)
			(layer "B.Fab")
		)
		(pad "1" smd circle
			(at 0.40005 0 180)
			(size 0 0)
			(layers "B.Cu" "B.Mask" "B.Paste")
			(net "P3V3_CLK_GEN_VDDMXCK_CK440")
		)
		(pad "2" smd circle
			(at -0.40005 0 180)
			(size 0 0)
			(layers "B.Cu" "B.Mask" "B.Paste")
			(net "GND")
		)
	)
	(footprint ""
		(layer "B.Cu")
		(at 160.549844 -299.699934)
		(property "Reference" "C3183"
			(at 0 0 0)
			(layer "B.SilkS")
			(hide yes)
			(effects
				(font
					(size 1.27 1.27)
				)
				(justify mirror)
			)
		)
		(property "Value" ""
			(at 0 0 0)
			(layer "B.Fab")
			(effects
				(font
					(size 1.27 1.27)
				)
				(justify mirror)
			)
		)
		(duplicate_pad_numbers_are_jumpers no)
		(fp_line
			(start -0.299974 -0.150114)
			(end -0.299974 0.150114)
			(stroke
				(width 0.1)
				(type default)
			)
			(layer "B.Fab")
		)
		(fp_line
			(start -0.299974 0.150114)
			(end 0.299974 0.150114)
			(stroke
				(width 0.1)
				(type default)
			)
			(layer "B.Fab")
		)
		(fp_line
			(start 0.299974 -0.150114)
			(end -0.299974 -0.150114)
			(stroke
				(width 0.1)
				(type default)
			)
			(layer "B.Fab")
		)
		(fp_line
			(start 0.299974 0.150114)
			(end 0.299974 -0.150114)
			(stroke
				(width 0.1)
				(type default)
			)
			(layer "B.Fab")
		)
		(pad "1" smd rect
			(at 0.2667 0 180)
			(size 0.3048 0.381)
			(layers "B.Cu" "B.Mask" "B.Paste")
			(net "P1V8_VDDA_PEX1")
		)
		(pad "2" smd rect
			(at -0.2667 0 180)
			(size 0.3048 0.381)
			(layers "B.Cu" "B.Mask" "B.Paste")
			(net "GND")
		)
	)
	(footprint ""
		(layer "B.Cu")
		(at 363.275118 -221.640908 90)
		(property "Reference" "R3503"
			(at 0 0 90)
			(layer "B.SilkS")
			(hide yes)
			(effects
				(font
					(size 1.27 1.27)
				)
				(justify mirror)
			)
		)
		(property "Value" ""
			(at 0 0 90)
			(layer "B.Fab")
			(effects
				(font
					(size 1.27 1.27)
				)
				(justify mirror)
			)
		)
		(duplicate_pad_numbers_are_jumpers no)
		(fp_line
			(start 0.7874 -0.4064)
			(end -0.7874 -0.4064)
			(stroke
				(width 0.1524)
				(type default)
			)
			(layer "B.SilkS")
		)
		(fp_line
			(start -0.7874 -0.4064)
			(end -0.7874 0.4064)
			(stroke
				(width 0.1524)
				(type default)
			)
			(layer "B.SilkS")
		)
		(fp_line
			(start 0.7874 0.4064)
			(end 0.7874 -0.4064)
			(stroke
				(width 0.1524)
				(type default)
			)
			(layer "B.SilkS")
		)
		(fp_line
			(start -0.7874 0.4064)
			(end 0.7874 0.4064)
			(stroke
				(width 0.1524)
				(type default)
			)
			(layer "B.SilkS")
		)
		(fp_line
			(start 0.67945 -0.305054)
			(end 0.12065 -0.305054)
			(stroke
				(width 0.1)
				(type default)
			)
			(layer "B.Fab")
		)
		(fp_line
			(start 0.12065 -0.305054)
			(end 0.12065 -0.2794)
			(stroke
				(width 0.1)
				(type default)
			)
			(layer "B.Fab")
		)
		(fp_line
			(start -0.12065 -0.3048)
			(end -0.67945 -0.3048)
			(stroke
				(width 0.1)
				(type default)
			)
			(layer "B.Fab")
		)
		(fp_line
			(start -0.67945 -0.3048)
			(end -0.67945 0.3048)
			(stroke
				(width 0.1)
				(type default)
			)
			(layer "B.Fab")
		)
		(fp_line
			(start 0.12065 -0.2794)
			(end -0.12065 -0.2794)
			(stroke
				(width 0.1)
				(type default)
			)
			(layer "B.Fab")
		)
		(fp_line
			(start -0.12065 -0.2794)
			(end -0.12065 -0.3048)
			(stroke
				(width 0.1)
				(type default)
			)
			(layer "B.Fab")
		)
		(fp_line
			(start 0.12065 0.2794)
			(end 0.12065 0.3048)
			(stroke
				(width 0.1)
				(type default)
			)
			(layer "B.Fab")
		)
		(fp_line
			(start -0.120396 0.2794)
			(end 0.12065 0.2794)
			(stroke
				(width 0.1)
				(type default)
			)
			(layer "B.Fab")
		)
		(fp_line
			(start 0.67945 0.3048)
			(end 0.67945 -0.305054)
			(stroke
				(width 0.1)
				(type default)
			)
			(layer "B.Fab")
		)
		(fp_line
			(start 0.12065 0.3048)
			(end 0.67945 0.3048)
			(stroke
				(width 0.1)
				(type default)
			)
			(layer "B.Fab")
		)
		(fp_line
			(start -0.120396 0.3048)
			(end -0.120396 0.2794)
			(stroke
				(width 0.1)
				(type default)
			)
			(layer "B.Fab")
		)
		(fp_line
			(start -0.67945 0.3048)
			(end -0.120396 0.3048)
			(stroke
				(width 0.1)
				(type default)
			)
			(layer "B.Fab")
		)
		(pad "1" smd circle
			(at 0.40005 0 270)
			(size 0 0)
			(layers "B.Cu" "B.Mask" "B.Paste")
			(net "SPI_PEX3_CLK_MUX")
		)
		(pad "2" smd circle
			(at -0.40005 0 270)
			(size 0 0)
			(layers "B.Cu" "B.Mask" "B.Paste")
			(net "SPI_PEX3_CLK_MUX_R")
		)
	)
	(footprint ""
		(layer "B.Cu")
		(at 65.370202 -296.37482)
		(property "Reference" "C1127"
			(at 0 0 0)
			(layer "B.SilkS")
			(hide yes)
			(effects
				(font
					(size 1.27 1.27)
				)
				(justify mirror)
			)
		)
		(property "Value" ""
			(at 0 0 0)
			(layer "B.Fab")
			(effects
				(font
					(size 1.27 1.27)
				)
				(justify mirror)
			)
		)
		(duplicate_pad_numbers_are_jumpers no)
		(fp_line
			(start -0.299974 -0.150114)
			(end -0.299974 0.150114)
			(stroke
				(width 0.1)
				(type default)
			)
			(layer "B.Fab")
		)
		(fp_line
			(start -0.299974 0.150114)
			(end 0.299974 0.150114)
			(stroke
				(width 0.1)
				(type default)
			)
			(layer "B.Fab")
		)
		(fp_line
			(start 0.299974 -0.150114)
			(end -0.299974 -0.150114)
			(stroke
				(width 0.1)
				(type default)
			)
			(layer "B.Fab")
		)
		(fp_line
			(start 0.299974 0.150114)
			(end 0.299974 -0.150114)
			(stroke
				(width 0.1)
				(type default)
			)
			(layer "B.Fab")
		)
		(pad "1" smd rect
			(at 0.2667 0 180)
			(size 0.3048 0.381)
			(layers "B.Cu" "B.Mask" "B.Paste")
			(net "P0V8_PEX0")
		)
		(pad "2" smd rect
			(at -0.2667 0 180)
			(size 0.3048 0.381)
			(layers "B.Cu" "B.Mask" "B.Paste")
			(net "GND")
		)
	)
)
